# T6G (Grand Teton) — schematic netlist excerpt (pin names and nets, part order shuffled) for the footprints in the layout excerpt that follows; sources: Cadence DE-HDL packaged netlist, KiCad conversion of 04192023_DAF0TMB3IC0_F0TG_MB_C_brd_V02_OCP.brd

R1525  Q_RES  0 5% EMPTY  pkg 0402LF  page 142 : A = OCP_V3_2_P3V3_PWRGD ; B = OCP_V3_2_P3V3_R3_PWRGD
R3582  Q_RES  2.2K 5% CHIP  pkg 0402LF  page 250 : A = P3V3_AUX ; B = SMB_IOEXP_3V3AUX_SCL
C750  Q_CAP_DIFFBUS  DIFF BUS_0.22UF 6.3V 20% X6S  pkg C0201  page 66 : \1\ = P5E_CPU1_P2_TX_C_DN<11> ; \2\ = P5E_CPU1_P2_TX_DN<11>

(kicad_pcb
	(version 20260206)
	(generator "pcbnew")
	(generator_version "10.0")
	(general
		(thickness 1.6)
		(legacy_teardrops no)
	)
	(paper "A4")
	(title_block
		(title "04192023_DAF0TMB3IC0_F0TG_MB_C_brd_V02_OCP.brd")
		(comment 1 "Grand Teton / footprints 4810-4812 of 8354")
	)
	(layers
		(0 "F.Cu" signal "TOP")
		(4 "In1.Cu" signal "GND")
		(6 "In2.Cu" signal "IN1")
		(8 "In3.Cu" signal "GND1")
		(10 "In4.Cu" signal "IN2")
		(12 "In5.Cu" signal "GND2")
		(14 "In6.Cu" signal "IN3")
		(16 "In7.Cu" signal "GND3")
		(18 "In8.Cu" signal "VCC")
		(20 "In9.Cu" signal "VCC1")
		(22 "In10.Cu" signal "GND4")
		(24 "In11.Cu" signal "IN4")
		(26 "In12.Cu" signal "GND5")
		(28 "In13.Cu" signal "IN5")
		(30 "In14.Cu" signal "GND6")
		(32 "In15.Cu" signal "IN6")
		(34 "In16.Cu" signal "GND7")
		(2 "B.Cu" signal "BOTTOM")
		(9 "F.Adhes" user "F.Adhesive")
		(11 "B.Adhes" user "B.Adhesive")
		(13 "F.Paste" user "Package Geometry/Pastemask Top")
		(15 "B.Paste" user "Package Geometry/Pastemask Bottom")
		(5 "F.SilkS" user "Ref Des/Silkscreen Top")
		(7 "B.SilkS" user "Ref Des/Silkscreen Bottom")
		(1 "F.Mask" user "Board Geometry/Soldermask Top")
		(3 "B.Mask" user "Board Geometry/Soldermask Bottom")
		(17 "Dwgs.User" user "User.Drawings")
		(19 "Cmts.User" user "User.Comments")
		(21 "Eco1.User" user "User.Eco1")
		(23 "Eco2.User" user "User.Eco2")
		(25 "Edge.Cuts" user "Board Geometry/Outline")
		(27 "Margin" user)
		(31 "F.CrtYd" user "Package Geometry/Place Bound Top")
		(29 "B.CrtYd" user "Package Geometry/Place Bound Bottom")
		(35 "F.Fab" user "Ref Des/Assembly Top")
		(33 "B.Fab" user "Ref Des/Assembly Bottom")
	)
	(footprint ""
		(layer "F.Cu")
		(at 63.25616 -56.98998)
		(property "Reference" "R1525"
			(at 0 0 0)
			(layer "F.SilkS")
			(hide yes)
			(effects
				(font
					(size 1.27 1.27)
				)
			)
		)
		(property "Value" ""
			(at 0 0 0)
			(layer "F.Fab")
			(effects
				(font
					(size 1.27 1.27)
				)
			)
		)
		(duplicate_pad_numbers_are_jumpers no)
		(fp_line
			(start -0.7874 -0.4064)
			(end 0.7874 -0.4064)
			(stroke
				(width 0.1524)
				(type default)
			)
			(layer "F.SilkS")
		)
		(fp_line
			(start -0.7874 0.4064)
			(end -0.7874 -0.4064)
			(stroke
				(width 0.1524)
				(type default)
			)
			(layer "F.SilkS")
		)
		(fp_line
			(start 0.7874 -0.4064)
			(end 0.7874 0.4064)
			(stroke
				(width 0.1524)
				(type default)
			)
			(layer "F.SilkS")
		)
		(fp_line
			(start 0.7874 0.4064)
			(end -0.7874 0.4064)
			(stroke
				(width 0.1524)
				(type default)
			)
			(layer "F.SilkS")
		)
		(fp_line
			(start -0.67945 -0.305054)
			(end -0.12065 -0.305054)
			(stroke
				(width 0.1)
				(type default)
			)
			(layer "F.Fab")
		)
		(fp_line
			(start -0.67945 0.3048)
			(end -0.67945 -0.305054)
			(stroke
				(width 0.1)
				(type default)
			)
			(layer "F.Fab")
		)
		(fp_line
			(start -0.12065 -0.305054)
			(end -0.12065 -0.2794)
			(stroke
				(width 0.1)
				(type default)
			)
			(layer "F.Fab")
		)
		(fp_line
			(start -0.12065 -0.2794)
			(end 0.12065 -0.2794)
			(stroke
				(width 0.1)
				(type default)
			)
			(layer "F.Fab")
		)
		(fp_line
			(start -0.12065 0.2794)
			(end -0.12065 0.3048)
			(stroke
				(width 0.1)
				(type default)
			)
			(layer "F.Fab")
		)
		(fp_line
			(start -0.12065 0.3048)
			(end -0.67945 0.3048)
			(stroke
				(width 0.1)
				(type default)
			)
			(layer "F.Fab")
		)
		(fp_line
			(start 0.120396 0.2794)
			(end -0.12065 0.2794)
			(stroke
				(width 0.1)
				(type default)
			)
			(layer "F.Fab")
		)
		(fp_line
			(start 0.120396 0.3048)
			(end 0.120396 0.2794)
			(stroke
				(width 0.1)
				(type default)
			)
			(layer "F.Fab")
		)
		(fp_line
			(start 0.12065 -0.3048)
			(end 0.67945 -0.3048)
			(stroke
				(width 0.1)
				(type default)
			)
			(layer "F.Fab")
		)
		(fp_line
			(start 0.12065 -0.2794)
			(end 0.12065 -0.3048)
			(stroke
				(width 0.1)
				(type default)
			)
			(layer "F.Fab")
		)
		(fp_line
			(start 0.67945 -0.3048)
			(end 0.67945 0.3048)
			(stroke
				(width 0.1)
				(type default)
			)
			(layer "F.Fab")
		)
		(fp_line
			(start 0.67945 0.3048)
			(end 0.120396 0.3048)
			(stroke
				(width 0.1)
				(type default)
			)
			(layer "F.Fab")
		)
		(pad "1" smd circle
			(at -0.40005 0)
			(size 0 0)
			(layers "F.Cu" "F.Mask" "F.Paste")
			(net "OCP_V3_2_P3V3_PWRGD")
		)
		(pad "2" smd circle
			(at 0.40005 0)
			(size 0 0)
			(layers "F.Cu" "F.Mask" "F.Paste")
			(net "OCP_V3_2_P3V3_R3_PWRGD")
		)
	)
	(footprint ""
		(layer "F.Cu")
		(at 277.352252 -117.50167)
		(property "Reference" "R3582"
			(at 0 0 0)
			(layer "F.SilkS")
			(hide yes)
			(effects
				(font
					(size 1.27 1.27)
				)
			)
		)
		(property "Value" ""
			(at 0 0 0)
			(layer "F.Fab")
			(effects
				(font
					(size 1.27 1.27)
				)
			)
		)
		(duplicate_pad_numbers_are_jumpers no)
		(fp_line
			(start -0.7874 -0.4064)
			(end 0.7874 -0.4064)
			(stroke
				(width 0.1524)
				(type default)
			)
			(layer "F.SilkS")
		)
		(fp_line
			(start -0.7874 0.4064)
			(end -0.7874 -0.4064)
			(stroke
				(width 0.1524)
				(type default)
			)
			(layer "F.SilkS")
		)
		(fp_line
			(start 0.7874 -0.4064)
			(end 0.7874 0.4064)
			(stroke
				(width 0.1524)
				(type default)
			)
			(layer "F.SilkS")
		)
		(fp_line
			(start 0.7874 0.4064)
			(end -0.7874 0.4064)
			(stroke
				(width 0.1524)
				(type default)
			)
			(layer "F.SilkS")
		)
		(fp_line
			(start -0.67945 -0.305054)
			(end -0.12065 -0.305054)
			(stroke
				(width 0.1)
				(type default)
			)
			(layer "F.Fab")
		)
		(fp_line
			(start -0.67945 0.3048)
			(end -0.67945 -0.305054)
			(stroke
				(width 0.1)
				(type default)
			)
			(layer "F.Fab")
		)
		(fp_line
			(start -0.12065 -0.305054)
			(end -0.12065 -0.2794)
			(stroke
				(width 0.1)
				(type default)
			)
			(layer "F.Fab")
		)
		(fp_line
			(start -0.12065 -0.2794)
			(end 0.12065 -0.2794)
			(stroke
				(width 0.1)
				(type default)
			)
			(layer "F.Fab")
		)
		(fp_line
			(start -0.12065 0.2794)
			(end -0.12065 0.3048)
			(stroke
				(width 0.1)
				(type default)
			)
			(layer "F.Fab")
		)
		(fp_line
			(start -0.12065 0.3048)
			(end -0.67945 0.3048)
			(stroke
				(width 0.1)
				(type default)
			)
			(layer "F.Fab")
		)
		(fp_line
			(start 0.120396 0.2794)
			(end -0.12065 0.2794)
			(stroke
				(width 0.1)
				(type default)
			)
			(layer "F.Fab")
		)
		(fp_line
			(start 0.120396 0.3048)
			(end 0.120396 0.2794)
			(stroke
				(width 0.1)
				(type default)
			)
			(layer "F.Fab")
		)
		(fp_line
			(start 0.12065 -0.3048)
			(end 0.67945 -0.3048)
			(stroke
				(width 0.1)
				(type default)
			)
			(layer "F.Fab")
		)
		(fp_line
			(start 0.12065 -0.2794)
			(end 0.12065 -0.3048)
			(stroke
				(width 0.1)
				(type default)
			)
			(layer "F.Fab")
		)
		(fp_line
			(start 0.67945 -0.3048)
			(end 0.67945 0.3048)
			(stroke
				(width 0.1)
				(type default)
			)
			(layer "F.Fab")
		)
		(fp_line
			(start 0.67945 0.3048)
			(end 0.120396 0.3048)
			(stroke
				(width 0.1)
				(type default)
			)
			(layer "F.Fab")
		)
		(pad "1" smd circle
			(at -0.40005 0)
			(size 0 0)
			(layers "F.Cu" "F.Mask" "F.Paste")
			(net "P3V3_AUX")
		)
		(pad "2" smd circle
			(at 0.40005 0)
			(size 0 0)
			(layers "F.Cu" "F.Mask" "F.Paste")
			(net "SMB_IOEXP_3V3AUX_SCL")
		)
	)
	(footprint ""
		(layer "F.Cu")
		(at 163.953444 -373.03583 -90)
		(property "Reference" "C750"
			(at 0 0 270)
			(layer "F.SilkS")
			(hide yes)
			(effects
				(font
					(size 1.27 1.27)
				)
			)
		)
		(property "Value" ""
			(at 0 0 270)
			(layer "F.Fab")
			(effects
				(font
					(size 1.27 1.27)
				)
			)
		)
		(duplicate_pad_numbers_are_jumpers no)
		(fp_line
			(start -0.299974 0.150114)
			(end -0.299974 -0.150114)
			(stroke
				(width 0.1)
				(type default)
			)
			(layer "F.Fab")
		)
		(fp_line
			(start 0.299974 0.150114)
			(end -0.299974 0.150114)
			(stroke
				(width 0.1)
				(type default)
			)
			(layer "F.Fab")
		)
		(fp_line
			(start -0.299974 -0.150114)
			(end 0.299974 -0.150114)
			(stroke
				(width 0.1)
				(type default)
			)
			(layer "F.Fab")
		)
		(fp_line
			(start 0.299974 -0.150114)
			(end 0.299974 0.150114)
			(stroke
				(width 0.1)
				(type default)
			)
			(layer "F.Fab")
		)
		(pad "1" smd rect
			(at -0.2667 0 270)
			(size 0.3048 0.381)
			(layers "F.Cu" "F.Mask" "F.Paste")
			(net "P5E_CPU1_P2_TX_C_DN<11>")
		)
		(pad "2" smd rect
			(at 0.2667 0 270)
			(size 0.3048 0.381)
			(layers "F.Cu" "F.Mask" "F.Paste")
			(net "P5E_CPU1_P2_TX_DN<11>")
		)
	)
)
